FILE_TYPE = CONNECTIVITY;
{Allegro Design Entry HDL 16.6-p007 (v16-6-112F) 10/10/2012}
"PAGE_NUMBER" = 105;
0"NC";
1"P3E_CPU0_PE1_PCH_RXP<15:8>";
2"P3E_CPU0_PE1_PCH_R_RXN<15:8>";
3"P3E_CPU0_PE1_PCH_R_RXP<15:8>";
4"P3E_CPU0_PE2_SS_C_TXN<15:0>";
5"P3E_CPU0_PE1_PCH_RXN<15:8>";
6"P3E_CPU0_PE1_PCH_TXP<15:8>";
7"P3E_CPU0_PE1_PCH_C_TXN<15:8>";
8"P3E_CPU0_PE2_SS_TXP<15:0>";
9"P3E_CPU0_PE1_PCH_TXN<15:8>";
10"P3E_CPU0_PE2_SS_C_TXP<15:0>";
11"P3E_CPU0_PE2_SS_TXN<15:0>";
12"P3E_CPU0_PE1_PCH_C_TXP<15:8>";
13"P3E_CPU0_PE1_PCH_RXP<11>";
14"P3E_CPU0_PE1_PCH_RXP<12>";
15"P3E_CPU0_PE1_PCH_R_RXP<13>";
16"P3E_CPU0_PE1_PCH_C_TXN<8>";
17"P3E_CPU0_PE1_PCH_C_TXN<9>";
18"P3E_CPU0_PE1_PCH_TXN<11>";
19"P3E_CPU0_PE1_PCH_C_TXN<14>";
20"P3E_CPU0_PE1_PCH_C_TXN<15>";
21"P3E_CPU0_PE1_PCH_C_TXN<10>";
22"P3E_CPU0_PE1_PCH_C_TXN<13>";
23"P3E_CPU0_PE1_PCH_TXP<8>";
24"P3E_CPU0_PE2_SS_C_TXN<13>";
25"P3E_CPU0_PE2_SS_TXN<11>";
26"P3E_CPU0_PE1_PCH_RXN<8>";
27"P3E_CPU0_PE1_PCH_R_RXN<15>";
28"P3E_CPU0_PE1_PCH_RXN<12>";
29"P3E_CPU0_PE1_PCH_TXP<13>";
30"P3E_CPU0_PE1_PCH_TXP<11>";
31"P3E_CPU0_PE1_PCH_C_TXP<14>";
32"P3E_CPU0_PE2_SS_C_TXP<2>";
33"P3E_CPU0_PE2_SS_TXN<1>";
34"P3E_CPU0_PE2_SS_C_TXN<8>";
35"P3E_CPU0_PE2_SS_TXN<8>";
36"P3E_CPU0_PE2_SS_C_TXP<8>";
37"P3E_CPU0_PE2_SS_TXP<8>";
38"P3E_CPU0_PE2_SS_C_TXP<4>";
39"P3E_CPU0_PE2_SS_C_TXP<6>";
40"P3E_CPU0_PE2_SS_TXP<7>";
41"P3E_CPU0_PE2_SS_TXP<3>";
42"P3E_CPU0_PE2_SS_TXP<9>";
43"P3E_CPU0_PE2_SS_TXP<12>";
44"P3E_CPU0_PE2_SS_TXN<7>";
45"P3E_CPU0_PE2_SS_TXN<6>";
46"P3E_CPU0_PE2_SS_C_TXP<0>";
47"P3E_CPU0_PE2_SS_C_TXP<7>";
48"P3E_CPU0_PE2_SS_TXN<9>";
49"P3E_CPU0_PE2_SS_C_TXN<0>";
50"P3E_CPU0_PE2_SS_TXN<10>";
51"P3E_CPU0_PE2_SS_C_TXN<15>";
52"P3E_CPU0_PE2_SS_C_TXN<14>";
53"P3E_CPU0_PE2_SS_C_TXN<12>";
54"P3E_CPU0_PE2_SS_C_TXN<11>";
55"P3E_CPU0_PE2_SS_C_TXN<9>";
56"P3E_CPU0_PE2_SS_C_TXN<10>";
57"P3E_CPU0_PE2_SS_C_TXN<5>";
58"P3E_CPU0_PE2_SS_C_TXN<4>";
59"P3E_CPU0_PE2_SS_C_TXN<3>";
60"P3E_CPU0_PE2_SS_C_TXN<2>";
61"P3E_CPU0_PE2_SS_C_TXN<1>";
62"P3E_CPU0_PE1_PCH_C_TXP<15>";
63"P3E_CPU0_PE1_PCH_C_TXP<13>";
64"P3E_CPU0_PE1_PCH_C_TXP<12>";
65"P3E_CPU0_PE1_PCH_TXP<15>";
66"P3E_CPU0_PE1_PCH_TXP<14>";
67"P3E_CPU0_PE1_PCH_TXP<12>";
68"P3E_CPU0_PE1_PCH_TXN<15>";
69"P3E_CPU0_PE1_PCH_TXN<13>";
70"P3E_CPU0_PE1_PCH_TXN<14>";
71"P3E_CPU0_PE1_PCH_TXN<12>";
72"P3E_CPU0_PE1_PCH_C_TXP<11>";
73"P3E_CPU0_PE1_PCH_C_TXP<9>";
74"P3E_CPU0_PE1_PCH_C_TXP<8>";
75"P3E_CPU0_PE1_PCH_C_TXP<10>";
76"P3E_CPU0_PE1_PCH_C_TXN<11>";
77"P3E_CPU0_PE2_SS_TXN<15>";
78"P3E_CPU0_PE2_SS_TXN<13>";
79"P3E_CPU0_PE2_SS_TXN<14>";
80"P3E_CPU0_PE2_SS_TXN<12>";
81"P3E_CPU0_PE2_SS_C_TXP<15>";
82"P3E_CPU0_PE2_SS_C_TXP<14>";
83"P3E_CPU0_PE2_SS_TXP<15>";
84"P3E_CPU0_PE2_SS_TXP<14>";
85"P3E_CPU0_PE2_SS_C_TXP<13>";
86"P3E_CPU0_PE2_SS_C_TXP<12>";
87"P3E_CPU0_PE2_SS_TXP<13>";
88"P3E_CPU0_PE1_PCH_RXN<15>";
89"P3E_CPU0_PE1_PCH_RXN<13>";
90"P3E_CPU0_PE1_PCH_RXN<11>";
91"P3E_CPU0_PE1_PCH_RXN<14>";
92"P3E_CPU0_PE1_PCH_R_RXN<14>";
93"P3E_CPU0_PE1_PCH_RXP<13>";
94"P3E_CPU0_PE1_PCH_R_RXN<12>";
95"P3E_CPU0_PE1_PCH_R_RXP<14>";
96"P3E_CPU0_PE1_PCH_R_RXP<12>";
97"P3E_CPU0_PE1_PCH_R_RXP<10>";
98"P3E_CPU0_PE2_SS_TXN<5>";
99"P3E_CPU0_PE2_SS_TXN<4>";
100"P3E_CPU0_PE2_SS_TXN<3>";
101"P3E_CPU0_PE2_SS_TXN<2>";
102"P3E_CPU0_PE1_PCH_R_RXN<10>";
103"P3E_CPU0_PE1_PCH_R_RXN<8>";
104"P3E_CPU0_PE2_SS_TXN<0>";
105"P3E_CPU0_PE2_SS_C_TXP<11>";
106"P3E_CPU0_PE2_SS_C_TXP<10>";
107"P3E_CPU0_PE2_SS_C_TXP<9>";
108"P3E_CPU0_PE2_SS_TXP<11>";
109"P3E_CPU0_PE2_SS_TXP<10>";
110"P3E_CPU0_PE2_SS_C_TXP<5>";
111"P3E_CPU0_PE2_SS_TXP<5>";
112"P3E_CPU0_PE2_SS_TXP<6>";
113"P3E_CPU0_PE2_SS_C_TXP<3>";
114"P3E_CPU0_PE2_SS_TXP<2>";
115"P3E_CPU0_PE2_SS_C_TXP<1>";
116"P3E_CPU0_PE2_SS_TXP<1>";
117"P3E_CPU0_PE2_SS_TXP<0>";
118"P3E_CPU0_PE2_SS_C_TXN<7>";
119"P3E_CPU0_PE1_PCH_TXN<10>";
120"P3E_CPU0_PE1_PCH_TXN<9>";
121"P3E_CPU0_PE1_PCH_TXN<8>";
122"P3E_CPU0_PE1_PCH_RXP<9>";
123"P3E_CPU0_PE2_SS_TXP<4>";
124"P3E_CPU0_PE1_PCH_C_TXN<12>";
125"P3E_CPU0_PE1_PCH_TXP<10>";
126"P3E_CPU0_PE1_PCH_TXP<9>";
127"P3E_CPU0_PE1_PCH_RXP<10>";
128"P3E_CPU0_PE1_PCH_RXN<9>";
129"P3E_CPU0_PE1_PCH_RXN<10>";
130"P3E_CPU0_PE1_PCH_RXP<8>";
131"P3E_CPU0_PE1_PCH_R_RXP<11>";
132"P3E_CPU0_PE1_PCH_R_RXP<9>";
133"P3E_CPU0_PE1_PCH_R_RXP<8>";
134"P3E_CPU0_PE2_SS_C_TXN<6>";
135"P3E_CPU0_PE1_PCH_R_RXP<15>";
136"P3E_CPU0_PE1_PCH_R_RXN<9>";
137"P3E_CPU0_PE1_PCH_R_RXN<11>";
138"P3E_CPU0_PE1_PCH_R_RXN<13>";
139"P3E_CPU0_PE1_PCH_RXP<15>";
140"P3E_CPU0_PE1_PCH_RXP<14>";
%"CAP"
"1","(1125,3650)","2","mstr_discrete","I1";
;
CDS_SEC"1"
PACK_TYPE"0402"
PART_NUMBER"A36096-155"
MATERIAL"X7R"
LOCATION"C7G24"
VOLTAGE"16V"
TOLERANCE"10%"
VALUE"0.22UF"
ROOM"OCP_STEERING"
CDS_LOCATION"C7G24"
SEC"1"
SEC_TYPE"0402"
CDS_LIB"mstr_discrete";
"A"
$PN"1"45;
"B"
$PN"2"134;
%"TAP"
"7","(-100,3100)","0","mstr_standard","I10";
;
CDS_LIB"mstr_standard"
BODY_TYPE"PLUMBING"
HDL_TAP"TRUE";
"B \NAC \NWC"4;
"S \NAC"
BN"12"53;
%"TAP"
"7","(100,3100)","0","mstr_standard","I11";
;
CDS_LIB"mstr_standard"
BODY_TYPE"PLUMBING"
HDL_TAP"TRUE";
"B \NAC \NWC"4;
"S \NAC"
BN"11"54;
%"CAP"
"1","(-100,3650)","2","mstr_discrete","I12";
;
CDS_SEC"1"
MATERIAL"X7R"
VOLTAGE"16V"
PACK_TYPE"0402"
TOLERANCE"10%"
VALUE"0.22UF"
PART_NUMBER"A36096-155"
LOCATION"C7G12"
ROOM"OCP_STEERING"
CDS_LOCATION"C7G12"
SEC"1"
CDS_LIB"mstr_discrete"
SEC_TYPE"0402";
"A"
$PN"1"80;
"B"
$PN"2"53;
%"CAP"
"1","(100,3350)","2","mstr_discrete","I13";
;
CDS_SEC"1"
MATERIAL"X7R"
VOLTAGE"16V"
PACK_TYPE"0402"
TOLERANCE"10%"
VALUE"0.22UF"
PART_NUMBER"A36096-155"
LOCATION"C7G13"
ROOM"OCP_STEERING"
CDS_LOCATION"C7G13"
SEC"1"
CDS_LIB"mstr_discrete"
SEC_TYPE"0402";
"A"
$PN"1"25;
"B"
$PN"2"54;
%"TAP"
"3","(-700,3900)","0","mstr_standard","I14";
;
CDS_LIB"mstr_standard"
BODY_TYPE"PLUMBING"
HDL_TAP"TRUE";
"B \NAC \NWC"11;
"S \NAC"
BN"15"77;
%"TAP"
"7","(-750,4100)","0","mstr_standard","I15";
;
CDS_LIB"mstr_standard"
BODY_TYPE"PLUMBING"
HDL_TAP"TRUE";
"B \NAC \NWC"10;
"S \NAC"
BN"15"81;
%"TAP"
"3","(1925,3900)","0","mstr_standard","I151";
;
CDS_LIB"mstr_standard"
BODY_TYPE"PLUMBING"
HDL_TAP"TRUE";
"B \NAC \NWC"11;
"S \NAC"
BN"2"101;
%"TAP"
"3","(50,4900)","0","mstr_standard","I152";
;
CDS_LIB"mstr_standard"
BODY_TYPE"PLUMBING"
HDL_TAP"TRUE";
"B \NAC \NWC"8;
"S \NAC"
BN"11"108;
%"CAP"
"1","(-1500,975)","2","mstr_discrete","I153";
;
CDS_SEC"1"
GROUP"PCIE_UPLINK"
MATERIAL"X7R"
VOLTAGE"16V"
PACK_TYPE"0402"
TOLERANCE"10%"
VALUE"0.22UF"
LOCATION"C6B18"
PART_NUMBER"A36096-155"
ROOM"OCP_STEERING"
CDS_LOCATION"C6B18"
SEC"1"
CDS_LIB"mstr_discrete"
SEC_TYPE"0402";
"A"
$PN"1"126;
"B"
$PN"2"73;
%"TAP"
"7","(-1350,1725)","0","mstr_standard","I154";
;
CDS_LIB"mstr_standard"
BODY_TYPE"PLUMBING"
HDL_TAP"TRUE";
"B \NAC \NWC"7;
"S \NAC"
BN"8"16;
%"TAP"
"3","(-2100,1525)","0","mstr_standard","I155";
;
CDS_LIB"mstr_standard"
BODY_TYPE"PLUMBING"
HDL_TAP"TRUE";
"B \NAC \NWC"6;
"S \NAC"
BN"12"67;
%"TAP"
"7","(-2350,1725)","0","mstr_standard","I156";
;
CDS_LIB"mstr_standard"
BODY_TYPE"PLUMBING"
HDL_TAP"TRUE";
"B \NAC \NWC"7;
"S \NAC"
BN"13"22;
%"TAP"
"7","(-2550,1725)","0","mstr_standard","I157";
;
CDS_LIB"mstr_standard"
BODY_TYPE"PLUMBING"
HDL_TAP"TRUE";
"B \NAC \NWC"7;
"S \NAC"
BN"14"19;
%"TAP"
"7","(-2750,1725)","0","mstr_standard","I158";
;
CDS_LIB"mstr_standard"
BODY_TYPE"PLUMBING"
HDL_TAP"TRUE";
"B \NAC \NWC"7;
"S \NAC"
BN"15"20;
%"TAP"
"3","(-1350,2525)","0","mstr_standard","I159";
;
CDS_LIB"mstr_standard"
BODY_TYPE"PLUMBING"
HDL_TAP"TRUE";
"B \NAC \NWC"9;
"S \NAC"
BN"8"121;
%"TAP"
"3","(-500,3900)","0","mstr_standard","I16";
;
CDS_LIB"mstr_standard"
BODY_TYPE"PLUMBING"
HDL_TAP"TRUE";
"B \NAC \NWC"11;
"S \NAC"
BN"14"79;
%"CAP"
"1","(-1350,2275)","2","mstr_discrete","I160";
;
CDS_SEC"1"
GROUP"PCIE_UPLINK"
MATERIAL"X7R"
VOLTAGE"16V"
TOLERANCE"10%"
VALUE"0.22UF"
LOCATION"C6B19"
PART_NUMBER"A36096-155"
PACK_TYPE"0402"
ROOM"OCP_STEERING"
CDS_LOCATION"C6B19"
SEC"1"
CDS_LIB"mstr_discrete"
SEC_TYPE"0402";
"A"
$PN"1"121;
"B"
$PN"2"16;
%"TAP"
"3","(-1550,2525)","0","mstr_standard","I161";
;
CDS_LIB"mstr_standard"
BODY_TYPE"PLUMBING"
HDL_TAP"TRUE";
"B \NAC \NWC"9;
"S \NAC"
BN"9"120;
%"TAP"
"3","(-1750,2525)","0","mstr_standard","I162";
;
CDS_LIB"mstr_standard"
BODY_TYPE"PLUMBING"
HDL_TAP"TRUE";
"B \NAC \NWC"9;
"S \NAC"
BN"10"119;
%"CAP"
"1","(-1750,2275)","2","mstr_discrete","I163";
;
CDS_SEC"1"
PART_NUMBER"A36096-155"
MATERIAL"X7R"
VALUE"0.22UF"
LOCATION"C6B15"
PACK_TYPE"0402"
TOLERANCE"10%"
VOLTAGE"16V"
GROUP"PCIE_UPLINK"
ROOM"OCP_STEERING"
CDS_LOCATION"C6B15"
SEC"1"
CDS_LIB"mstr_discrete"
SEC_TYPE"0402";
"A"
$PN"1"119;
"B"
$PN"2"21;
%"TAP"
"3","(-2150,2525)","0","mstr_standard","I164";
;
CDS_LIB"mstr_standard"
BODY_TYPE"PLUMBING"
HDL_TAP"TRUE";
"B \NAC \NWC"9;
"S \NAC"
BN"12"71;
%"TAP"
"3","(-1950,2525)","0","mstr_standard","I165";
;
CDS_LIB"mstr_standard"
BODY_TYPE"PLUMBING"
HDL_TAP"TRUE";
"B \NAC \NWC"9;
"S \NAC"
BN"11"18;
%"CAP"
"1","(-2150,2275)","2","mstr_discrete","I166";
;
CDS_SEC"1"
PACK_TYPE"0402"
PART_NUMBER"A36096-155"
MATERIAL"X7R"
TOLERANCE"10%"
VOLTAGE"16V"
VALUE"0.22UF"
LOCATION"C6B11"
GROUP"PCIE_UPLINK"
ROOM"OCP_STEERING"
CDS_LOCATION"C6B11"
SEC"1"
CDS_LIB"mstr_discrete"
SEC_TYPE"0402";
"A"
$PN"1"71;
"B"
$PN"2"124;
%"TAP"
"3","(-2350,2525)","0","mstr_standard","I167";
;
CDS_LIB"mstr_standard"
BODY_TYPE"PLUMBING"
HDL_TAP"TRUE";
"B \NAC \NWC"9;
"S \NAC"
BN"13"69;
%"TAP"
"3","(-2550,2525)","0","mstr_standard","I168";
;
CDS_LIB"mstr_standard"
BODY_TYPE"PLUMBING"
HDL_TAP"TRUE";
"B \NAC \NWC"9;
"S \NAC"
BN"14"70;
%"CAP"
"1","(-2550,2275)","2","mstr_discrete","I169";
;
CDS_SEC"1"
VOLTAGE"16V"
MATERIAL"X7R"
PACK_TYPE"0402"
TOLERANCE"10%"
VALUE"0.22UF"
PART_NUMBER"A36096-155"
LOCATION"C6B6"
GROUP"PCIE_UPLINK"
ROOM"OCP_STEERING"
CDS_LOCATION"C6B6"
SEC"1"
CDS_LIB"mstr_discrete"
SEC_TYPE"0402";
"A"
$PN"1"70;
"B"
$PN"2"19;
%"TAP"
"7","(-550,4100)","0","mstr_standard","I17";
;
CDS_LIB"mstr_standard"
BODY_TYPE"PLUMBING"
HDL_TAP"TRUE";
"B \NAC \NWC"10;
"S \NAC"
BN"14"82;
%"TAP"
"3","(-2750,2525)","0","mstr_standard","I170";
;
CDS_LIB"mstr_standard"
BODY_TYPE"PLUMBING"
HDL_TAP"TRUE";
"B \NAC \NWC"9;
"S \NAC"
BN"15"68;
%"TAP"
"3","(-1300,1525)","0","mstr_standard","I172";
;
CDS_LIB"mstr_standard"
BODY_TYPE"PLUMBING"
HDL_TAP"TRUE";
"B \NAC \NWC"6;
"S \NAC"
BN"8"23;
%"CAP"
"1","(-1300,1275)","2","mstr_discrete","I173";
;
CDS_SEC"1"
GROUP"PCIE_UPLINK"
TOLERANCE"10%"
MATERIAL"X7R"
PACK_TYPE"0402"
PART_NUMBER"A36096-155"
VALUE"0.22UF"
VOLTAGE"16V"
LOCATION"C6B20"
ROOM"OCP_STEERING"
CDS_LOCATION"C6B20"
SEC"1"
CDS_LIB"mstr_discrete"
SEC_TYPE"0402";
"A"
$PN"1"23;
"B"
$PN"2"74;
%"TAP"
"7","(-1300,725)","0","mstr_standard","I174";
;
CDS_LIB"mstr_standard"
BODY_TYPE"PLUMBING"
HDL_TAP"TRUE";
"B \NAC \NWC"12;
"S \NAC"
BN"8"74;
%"CAP"
"1","(-1550,1975)","2","mstr_discrete","I175";
;
CDS_SEC"1"
GROUP"PCIE_UPLINK"
PART_NUMBER"A36096-155"
MATERIAL"X7R"
LOCATION"C6B17"
TOLERANCE"10%"
VOLTAGE"16V"
VALUE"0.22UF"
PACK_TYPE"0402"
ROOM"OCP_STEERING"
CDS_LOCATION"C6B17"
SEC"1"
CDS_LIB"mstr_discrete"
SEC_TYPE"0402";
"A"
$PN"1"120;
"B"
$PN"2"17;
%"TAP"
"3","(-1500,1525)","0","mstr_standard","I176";
;
CDS_LIB"mstr_standard"
BODY_TYPE"PLUMBING"
HDL_TAP"TRUE";
"B \NAC \NWC"6;
"S \NAC"
BN"9"126;
%"TAP"
"7","(-1550,1725)","0","mstr_standard","I177";
;
CDS_LIB"mstr_standard"
BODY_TYPE"PLUMBING"
HDL_TAP"TRUE";
"B \NAC \NWC"7;
"S \NAC"
BN"9"17;
%"TAP"
"7","(-1750,1725)","0","mstr_standard","I178";
;
CDS_LIB"mstr_standard"
BODY_TYPE"PLUMBING"
HDL_TAP"TRUE";
"B \NAC \NWC"7;
"S \NAC"
BN"10"21;
%"TAP"
"3","(-1700,1525)","0","mstr_standard","I179";
;
CDS_LIB"mstr_standard"
BODY_TYPE"PLUMBING"
HDL_TAP"TRUE";
"B \NAC \NWC"6;
"S \NAC"
BN"10"125;
%"TAP"
"3","(-300,3900)","0","mstr_standard","I18";
;
CDS_LIB"mstr_standard"
BODY_TYPE"PLUMBING"
HDL_TAP"TRUE";
"B \NAC \NWC"11;
"S \NAC"
BN"13"78;
%"CAP"
"1","(-1700,1275)","2","mstr_discrete","I180";
;
CDS_SEC"1"
GROUP"PCIE_UPLINK"
LOCATION"C6B16"
VALUE"0.22UF"
MATERIAL"X7R"
VOLTAGE"16V"
PACK_TYPE"0402"
TOLERANCE"10%"
PART_NUMBER"A36096-155"
ROOM"OCP_STEERING"
CDS_LOCATION"C6B16"
SEC"1"
CDS_LIB"mstr_discrete"
SEC_TYPE"0402";
"A"
$PN"1"125;
"B"
$PN"2"75;
%"CAP"
"1","(-1950,1975)","2","mstr_discrete","I181";
;
CDS_SEC"1"
GROUP"PCIE_UPLINK"
PACK_TYPE"0402"
PART_NUMBER"A36096-155"
MATERIAL"X7R"
VALUE"0.22UF"
TOLERANCE"10%"
VOLTAGE"16V"
LOCATION"C6B14"
ROOM"OCP_STEERING"
CDS_LOCATION"C6B14"
SEC"1"
CDS_LIB"mstr_discrete"
SEC_TYPE"0402";
"A"
$PN"1"18;
"B"
$PN"2"76;
%"TAP"
"3","(-1900,1525)","0","mstr_standard","I182";
;
CDS_LIB"mstr_standard"
BODY_TYPE"PLUMBING"
HDL_TAP"TRUE";
"B \NAC \NWC"6;
"S \NAC"
BN"11"30;
%"TAP"
"7","(-1950,1725)","0","mstr_standard","I183";
;
CDS_LIB"mstr_standard"
BODY_TYPE"PLUMBING"
HDL_TAP"TRUE";
"B \NAC \NWC"7;
"S \NAC"
BN"11"76;
%"TAP"
"7","(-2150,1725)","0","mstr_standard","I184";
;
CDS_LIB"mstr_standard"
BODY_TYPE"PLUMBING"
HDL_TAP"TRUE";
"B \NAC \NWC"7;
"S \NAC"
BN"12"124;
%"CAP"
"1","(-2350,1975)","2","mstr_discrete","I185";
;
CDS_SEC"1"
LOCATION"C6B9"
MATERIAL"X7R"
PACK_TYPE"0402"
PART_NUMBER"A36096-155"
TOLERANCE"10%"
VOLTAGE"16V"
VALUE"0.22UF"
GROUP"PCIE_UPLINK"
ROOM"OCP_STEERING"
CDS_LOCATION"C6B9"
SEC"1"
CDS_LIB"mstr_discrete"
SEC_TYPE"0402";
"A"
$PN"1"69;
"B"
$PN"2"22;
%"TAP"
"3","(-2300,1525)","0","mstr_standard","I186";
;
CDS_LIB"mstr_standard"
BODY_TYPE"PLUMBING"
HDL_TAP"TRUE";
"B \NAC \NWC"6;
"S \NAC"
BN"13"29;
%"CAP"
"1","(-2100,1275)","2","mstr_discrete","I187";
;
CDS_SEC"1"
GROUP"PCIE_UPLINK"
VALUE"0.22UF"
TOLERANCE"10%"
MATERIAL"X7R"
PART_NUMBER"A36096-155"
VOLTAGE"16V"
PACK_TYPE"0402"
LOCATION"C6B12"
ROOM"OCP_STEERING"
CDS_LOCATION"C6B12"
SEC"1"
CDS_LIB"mstr_discrete"
SEC_TYPE"0402";
"A"
$PN"1"67;
"B"
$PN"2"64;
%"TAP"
"7","(-1500,725)","0","mstr_standard","I188";
;
CDS_LIB"mstr_standard"
BODY_TYPE"PLUMBING"
HDL_TAP"TRUE";
"B \NAC \NWC"12;
"S \NAC"
BN"9"73;
%"CAP"
"1","(-1900,975)","2","mstr_discrete","I189";
;
CDS_SEC"1"
GROUP"PCIE_UPLINK"
MATERIAL"X7R"
VOLTAGE"16V"
PACK_TYPE"0402"
TOLERANCE"10%"
VALUE"0.22UF"
PART_NUMBER"A36096-155"
LOCATION"C6B13"
ROOM"OCP_STEERING"
CDS_LOCATION"C6B13"
SEC"1"
CDS_LIB"mstr_discrete"
SEC_TYPE"0402";
"A"
$PN"1"30;
"B"
$PN"2"72;
%"TAP"
"7","(-350,4100)","0","mstr_standard","I19";
;
CDS_LIB"mstr_standard"
BODY_TYPE"PLUMBING"
HDL_TAP"TRUE";
"B \NAC \NWC"10;
"S \NAC"
BN"13"85;
%"TAP"
"7","(-1700,725)","0","mstr_standard","I190";
;
CDS_LIB"mstr_standard"
BODY_TYPE"PLUMBING"
HDL_TAP"TRUE";
"B \NAC \NWC"12;
"S \NAC"
BN"10"75;
%"TAP"
"7","(-1900,725)","0","mstr_standard","I191";
;
CDS_LIB"mstr_standard"
BODY_TYPE"PLUMBING"
HDL_TAP"TRUE";
"B \NAC \NWC"12;
"S \NAC"
BN"11"72;
%"TAP"
"7","(-2100,725)","0","mstr_standard","I192";
;
CDS_LIB"mstr_standard"
BODY_TYPE"PLUMBING"
HDL_TAP"TRUE";
"B \NAC \NWC"12;
"S \NAC"
BN"12"64;
%"CAP"
"1","(-2300,975)","2","mstr_discrete","I193";
;
CDS_SEC"1"
GROUP"PCIE_UPLINK"
LOCATION"C6B10"
VALUE"0.22UF"
MATERIAL"X7R"
VOLTAGE"16V"
PACK_TYPE"0402"
TOLERANCE"10%"
PART_NUMBER"A36096-155"
ROOM"OCP_STEERING"
CDS_LOCATION"C6B10"
SEC"1"
CDS_LIB"mstr_discrete"
SEC_TYPE"0402";
"A"
$PN"1"29;
"B"
$PN"2"63;
%"TAP"
"7","(-2300,725)","0","mstr_standard","I194";
;
CDS_LIB"mstr_standard"
BODY_TYPE"PLUMBING"
HDL_TAP"TRUE";
"B \NAC \NWC"12;
"S \NAC"
BN"13"63;
%"TAP"
"3","(-2500,1525)","0","mstr_standard","I195";
;
CDS_LIB"mstr_standard"
BODY_TYPE"PLUMBING"
HDL_TAP"TRUE";
"B \NAC \NWC"6;
"S \NAC"
BN"14"66;
%"CAP"
"1","(-2750,1975)","2","mstr_discrete","I196";
;
CDS_SEC"1"
VALUE"0.22UF"
VOLTAGE"16V"
MATERIAL"X7R"
PART_NUMBER"A36096-155"
LOCATION"C6B4"
TOLERANCE"10%"
PACK_TYPE"0402"
GROUP"PCIE_UPLINK"
ROOM"OCP_STEERING"
CDS_LOCATION"C6B4"
SEC"1"
CDS_LIB"mstr_discrete"
SEC_TYPE"0402";
"A"
$PN"1"68;
"B"
$PN"2"20;
%"TAP"
"3","(-2700,1525)","0","mstr_standard","I197";
;
CDS_LIB"mstr_standard"
BODY_TYPE"PLUMBING"
HDL_TAP"TRUE";
"B \NAC \NWC"6;
"S \NAC"
BN"15"65;
%"CAP"
"1","(-2500,1275)","2","mstr_discrete","I198";
;
CDS_SEC"1"
GROUP"PCIE_UPLINK"
MATERIAL"X7R"
VOLTAGE"16V"
PACK_TYPE"0402"
TOLERANCE"10%"
VALUE"0.22UF"
PART_NUMBER"A36096-155"
LOCATION"C6B8"
ROOM"OCP_STEERING"
CDS_LOCATION"C6B8"
SEC"1"
CDS_LIB"mstr_discrete"
SEC_TYPE"0402";
"A"
$PN"1"66;
"B"
$PN"2"31;
%"CAP"
"1","(-750,4350)","2","mstr_discrete","I20";
;
CDS_SEC"1"
MATERIAL"X7R"
VOLTAGE"16V"
PACK_TYPE"0402"
TOLERANCE"10%"
VALUE"0.22UF"
PART_NUMBER"A36096-155"
LOCATION"C7G5"
ROOM"OCP_STEERING"
CDS_LOCATION"C7G5"
SEC"1"
CDS_LIB"mstr_discrete"
SEC_TYPE"0402";
"A"
$PN"1"83;
"B"
$PN"2"81;
%"TAP"
"7","(-2500,725)","0","mstr_standard","I200";
;
CDS_LIB"mstr_standard"
BODY_TYPE"PLUMBING"
HDL_TAP"TRUE";
"B \NAC \NWC"12;
"S \NAC"
BN"14"31;
%"CAP"
"1","(-2700,975)","2","mstr_discrete","I201";
;
CDS_SEC"1"
GROUP"PCIE_UPLINK"
MATERIAL"X7R"
VOLTAGE"16V"
PACK_TYPE"0402"
TOLERANCE"10%"
VALUE"0.22UF"
PART_NUMBER"A36096-155"
LOCATION"C6B5"
ROOM"OCP_STEERING"
CDS_LOCATION"C6B5"
SEC"1"
CDS_LIB"mstr_discrete"
SEC_TYPE"0402";
"A"
$PN"1"65;
"B"
$PN"2"62;
%"TAP"
"7","(-2700,725)","0","mstr_standard","I202";
;
CDS_LIB"mstr_standard"
BODY_TYPE"PLUMBING"
HDL_TAP"TRUE";
"B \NAC \NWC"12;
"S \NAC"
BN"15"62;
%"CAP"
"1","(1800,2025)","2","mstr_discrete","I205";
;
LOCATION"C3M25"
VOLTAGE"16V"
PACK_TYPE"0402"
PART_NUMBER"A36096-155"
VALUE"0.22UF"
MATERIAL"X7R"
TOLERANCE"10%"
GROUP"PCIE_UPLINK"
ROOM"OCP_STEERING"
CDS_LOCATION"C3M25"
$SEC"1"
CDS_SEC"1"
CDS_LIB"mstr_discrete";
"A"
$PN"1"131;
"B"
$PN"2"13;
%"CAP"
"1","(2400,2325)","2","mstr_discrete","I206";
;
GROUP"PCIE_UPLINK"
VALUE"0.22UF"
PACK_TYPE"0402"
MATERIAL"X7R"
TOLERANCE"10%"
VOLTAGE"16V"
LOCATION"C3M34"
PART_NUMBER"A36096-155"
ROOM"OCP_STEERING"
CDS_LOCATION"C3M34"
$SEC"1"
CDS_SEC"1"
CDS_LIB"mstr_discrete";
"A"
$PN"1"133;
"B"
$PN"2"130;
%"TAP"
"3","(2400,2575)","0","mstr_standard","I209";
;
CDS_LIB"mstr_standard"
BODY_TYPE"PLUMBING"
HDL_TAP"TRUE";
"B \NAC \NWC"3;
"S \NAC"
BN"8"133;
%"CAP"
"1","(-350,4350)","2","mstr_discrete","I21";
;
CDS_SEC"1"
MATERIAL"X7R"
VOLTAGE"16V"
PACK_TYPE"0402"
TOLERANCE"10%"
VALUE"0.22UF"
PART_NUMBER"A36096-155"
LOCATION"C7G9"
ROOM"OCP_STEERING"
CDS_LOCATION"C7G9"
SEC"1"
CDS_LIB"mstr_discrete"
SEC_TYPE"0402";
"A"
$PN"1"87;
"B"
$PN"2"85;
%"TAP"
"3","(2200,2575)","0","mstr_standard","I210";
;
CDS_LIB"mstr_standard"
BODY_TYPE"PLUMBING"
HDL_TAP"TRUE";
"B \NAC \NWC"3;
"S \NAC"
BN"9"132;
%"TAP"
"3","(2000,2575)","0","mstr_standard","I211";
;
CDS_LIB"mstr_standard"
BODY_TYPE"PLUMBING"
HDL_TAP"TRUE";
"B \NAC \NWC"3;
"S \NAC"
BN"10"97;
%"CAP"
"1","(2000,2325)","2","mstr_discrete","I212";
;
GROUP"PCIE_UPLINK"
VALUE"0.22UF"
MATERIAL"X7R"
PART_NUMBER"A36096-155"
PACK_TYPE"0402"
VOLTAGE"16V"
TOLERANCE"10%"
LOCATION"C3M28"
ROOM"OCP_STEERING"
CDS_LOCATION"C3M28"
$SEC"1"
CDS_SEC"1"
CDS_LIB"mstr_discrete";
"A"
$PN"1"97;
"B"
$PN"2"127;
%"TAP"
"3","(1800,2575)","0","mstr_standard","I213";
;
CDS_LIB"mstr_standard"
BODY_TYPE"PLUMBING"
HDL_TAP"TRUE";
"B \NAC \NWC"3;
"S \NAC"
BN"11"131;
%"TAP"
"7","(2400,1775)","0","mstr_standard","I214";
;
CDS_LIB"mstr_standard"
BODY_TYPE"PLUMBING"
HDL_TAP"TRUE";
"B \NAC \NWC"1;
"S \NAC"
BN"8"130;
%"TAP"
"3","(2450,1575)","0","mstr_standard","I215";
;
CDS_LIB"mstr_standard"
BODY_TYPE"PLUMBING"
HDL_TAP"TRUE";
"B \NAC \NWC"2;
"S \NAC"
BN"8"103;
%"TAP"
"3","(2250,1575)","0","mstr_standard","I216";
;
CDS_LIB"mstr_standard"
BODY_TYPE"PLUMBING"
HDL_TAP"TRUE";
"B \NAC \NWC"2;
"S \NAC"
BN"9"136;
%"CAP"
"1","(2450,1325)","2","mstr_discrete","I217";
;
TOLERANCE"10%"
MATERIAL"X7R"
VALUE"0.22UF"
VOLTAGE"16V"
LOCATION"C3M33"
PART_NUMBER"A36096-155"
PACK_TYPE"0402"
GROUP"PCIE_UPLINK"
ROOM"OCP_STEERING"
CDS_LOCATION"C3M33"
$SEC"1"
CDS_SEC"1"
CDS_LIB"mstr_discrete";
"A"
$PN"1"103;
"B"
$PN"2"26;
%"CAP"
"1","(2200,2025)","2","mstr_discrete","I218";
;
VALUE"0.22UF"
TOLERANCE"10%"
MATERIAL"X7R"
VOLTAGE"16V"
PART_NUMBER"A36096-155"
LOCATION"C3M36"
PACK_TYPE"0402"
GROUP"PCIE_UPLINK"
ROOM"OCP_STEERING"
CDS_LOCATION"C3M36"
$SEC"1"
CDS_SEC"1"
CDS_LIB"mstr_discrete";
"A"
$PN"1"132;
"B"
$PN"2"122;
%"TAP"
"7","(2200,1775)","0","mstr_standard","I219";
;
CDS_LIB"mstr_standard"
BODY_TYPE"PLUMBING"
HDL_TAP"TRUE";
"B \NAC \NWC"1;
"S \NAC"
BN"9"122;
%"CAP"
"1","(-550,4650)","2","mstr_discrete","I22";
;
CDS_SEC"1"
MATERIAL"X7R"
VOLTAGE"16V"
PACK_TYPE"0402"
TOLERANCE"10%"
VALUE"0.22UF"
PART_NUMBER"A36096-155"
LOCATION"C7G8"
ROOM"OCP_STEERING"
CDS_LOCATION"C7G8"
SEC"1"
CDS_LIB"mstr_discrete"
SEC_TYPE"0402";
"A"
$PN"1"84;
"B"
$PN"2"82;
%"TAP"
"7","(2000,1775)","0","mstr_standard","I220";
;
CDS_LIB"mstr_standard"
BODY_TYPE"PLUMBING"
HDL_TAP"TRUE";
"B \NAC \NWC"1;
"S \NAC"
BN"10"127;
%"TAP"
"7","(1800,1775)","0","mstr_standard","I221";
;
CDS_LIB"mstr_standard"
BODY_TYPE"PLUMBING"
HDL_TAP"TRUE";
"B \NAC \NWC"1;
"S \NAC"
BN"11"13;
%"TAP"
"3","(2050,1575)","0","mstr_standard","I222";
;
CDS_LIB"mstr_standard"
BODY_TYPE"PLUMBING"
HDL_TAP"TRUE";
"B \NAC \NWC"2;
"S \NAC"
BN"10"102;
%"CAP"
"1","(2050,1325)","2","mstr_discrete","I223";
;
TOLERANCE"10%"
LOCATION"C3M32"
MATERIAL"X7R"
VOLTAGE"16V"
PACK_TYPE"0402"
VALUE"0.22UF"
PART_NUMBER"A36096-155"
GROUP"PCIE_UPLINK"
ROOM"OCP_STEERING"
CDS_LOCATION"C3M32"
$SEC"1"
CDS_SEC"1"
CDS_LIB"mstr_discrete";
"A"
$PN"1"102;
"B"
$PN"2"129;
%"TAP"
"3","(1850,1575)","0","mstr_standard","I224";
;
CDS_LIB"mstr_standard"
BODY_TYPE"PLUMBING"
HDL_TAP"TRUE";
"B \NAC \NWC"2;
"S \NAC"
BN"11"137;
%"CAP"
"1","(2250,1025)","2","mstr_discrete","I225";
;
PART_NUMBER"A36096-155"
PACK_TYPE"0402"
TOLERANCE"10%"
MATERIAL"X7R"
VOLTAGE"16V"
VALUE"0.22UF"
LOCATION"C3M35"
GROUP"PCIE_UPLINK"
ROOM"OCP_STEERING"
CDS_LOCATION"C3M35"
$SEC"1"
CDS_SEC"1"
CDS_LIB"mstr_discrete";
"A"
$PN"1"136;
"B"
$PN"2"128;
%"TAP"
"7","(2250,775)","0","mstr_standard","I226";
;
CDS_LIB"mstr_standard"
BODY_TYPE"PLUMBING"
HDL_TAP"TRUE";
"B \NAC \NWC"5;
"S \NAC"
BN"9"128;
%"TAP"
"7","(2450,775)","0","mstr_standard","I227";
;
CDS_LIB"mstr_standard"
BODY_TYPE"PLUMBING"
HDL_TAP"TRUE";
"B \NAC \NWC"5;
"S \NAC"
BN"8"26;
%"TAP"
"7","(2050,775)","0","mstr_standard","I228";
;
CDS_LIB"mstr_standard"
BODY_TYPE"PLUMBING"
HDL_TAP"TRUE";
"B \NAC \NWC"5;
"S \NAC"
BN"10"129;
%"CAP"
"1","(1850,1025)","2","mstr_discrete","I229";
;
VALUE"0.22UF"
TOLERANCE"10%"
MATERIAL"X7R"
VOLTAGE"16V"
PACK_TYPE"0402"
PART_NUMBER"A36096-155"
LOCATION"C3M26"
GROUP"PCIE_UPLINK"
ROOM"OCP_STEERING"
CDS_LOCATION"C3M26"
$SEC"1"
CDS_SEC"1"
CDS_LIB"mstr_discrete";
"A"
$PN"1"137;
"B"
$PN"2"90;
%"TAP"
"3","(-100,3900)","0","mstr_standard","I23";
;
CDS_LIB"mstr_standard"
BODY_TYPE"PLUMBING"
HDL_TAP"TRUE";
"B \NAC \NWC"11;
"S \NAC"
BN"12"80;
%"TAP"
"7","(1850,775)","0","mstr_standard","I230";
;
CDS_LIB"mstr_standard"
BODY_TYPE"PLUMBING"
HDL_TAP"TRUE";
"B \NAC \NWC"5;
"S \NAC"
BN"11"90;
%"TAP"
"3","(1600,2575)","0","mstr_standard","I231";
;
CDS_LIB"mstr_standard"
BODY_TYPE"PLUMBING"
HDL_TAP"TRUE";
"B \NAC \NWC"3;
"S \NAC"
BN"12"96;
%"CAP"
"1","(1600,2325)","2","mstr_discrete","I232";
;
GROUP"PCIE_UPLINK"
LOCATION"C3M3"
VALUE"0.22UF"
MATERIAL"X7R"
VOLTAGE"16V"
TOLERANCE"10%"
PART_NUMBER"A36096-155"
PACK_TYPE"0402"
ROOM"OCP_STEERING"
CDS_LOCATION"C3M3"
$SEC"1"
CDS_SEC"1"
CDS_LIB"mstr_discrete";
"A"
$PN"1"96;
"B"
$PN"2"14;
%"TAP"
"3","(1400,2575)","0","mstr_standard","I233";
;
CDS_LIB"mstr_standard"
BODY_TYPE"PLUMBING"
HDL_TAP"TRUE";
"B \NAC \NWC"3;
"S \NAC"
BN"13"15;
%"CAP"
"1","(1200,2325)","2","mstr_discrete","I234";
;
GROUP"PCIE_UPLINK"
PACK_TYPE"0402"
MATERIAL"X7R"
VOLTAGE"16V"
VALUE"0.22UF"
PART_NUMBER"A36096-155"
LOCATION"C3M11"
TOLERANCE"10%"
ROOM"OCP_STEERING"
CDS_LOCATION"C3M11"
$SEC"1"
CDS_SEC"1"
CDS_LIB"mstr_discrete";
"A"
$PN"1"95;
"B"
$PN"2"140;
%"TAP"
"3","(1200,2575)","0","mstr_standard","I235";
;
CDS_LIB"mstr_standard"
BODY_TYPE"PLUMBING"
HDL_TAP"TRUE";
"B \NAC \NWC"3;
"S \NAC"
BN"14"95;
%"TAP"
"3","(1000,2575)","0","mstr_standard","I236";
;
CDS_LIB"mstr_standard"
BODY_TYPE"PLUMBING"
HDL_TAP"TRUE";
"B \NAC \NWC"3;
"S \NAC"
BN"15"135;
%"TAP"
"7","(1600,1775)","0","mstr_standard","I238";
;
CDS_LIB"mstr_standard"
BODY_TYPE"PLUMBING"
HDL_TAP"TRUE";
"B \NAC \NWC"1;
"S \NAC"
BN"12"14;
%"CAP"
"1","(1400,2025)","2","mstr_discrete","I239";
;
GROUP"PCIE_UPLINK"
VOLTAGE"16V"
MATERIAL"X7R"
PACK_TYPE"0402"
PART_NUMBER"A36096-155"
LOCATION"C3M13"
VALUE"0.22UF"
TOLERANCE"10%"
ROOM"OCP_STEERING"
CDS_LOCATION"C3M13"
$SEC"1"
CDS_SEC"1"
CDS_LIB"mstr_discrete";
"A"
$PN"1"15;
"B"
$PN"2"93;
%"TAP"
"7","(-150,4100)","0","mstr_standard","I24";
;
CDS_LIB"mstr_standard"
BODY_TYPE"PLUMBING"
HDL_TAP"TRUE";
"B \NAC \NWC"10;
"S \NAC"
BN"12"86;
%"TAP"
"7","(1400,1775)","0","mstr_standard","I240";
;
CDS_LIB"mstr_standard"
BODY_TYPE"PLUMBING"
HDL_TAP"TRUE";
"B \NAC \NWC"1;
"S \NAC"
BN"13"93;
%"TAP"
"7","(1200,1775)","0","mstr_standard","I241";
;
CDS_LIB"mstr_standard"
BODY_TYPE"PLUMBING"
HDL_TAP"TRUE";
"B \NAC \NWC"1;
"S \NAC"
BN"14"140;
%"TAP"
"3","(1650,1575)","0","mstr_standard","I242";
;
CDS_LIB"mstr_standard"
BODY_TYPE"PLUMBING"
HDL_TAP"TRUE";
"B \NAC \NWC"2;
"S \NAC"
BN"12"94;
%"TAP"
"3","(1450,1575)","0","mstr_standard","I243";
;
CDS_LIB"mstr_standard"
BODY_TYPE"PLUMBING"
HDL_TAP"TRUE";
"B \NAC \NWC"2;
"S \NAC"
BN"13"138;
%"CAP"
"1","(1650,1325)","2","mstr_discrete","I244";
;
PACK_TYPE"0402"
PART_NUMBER"A36096-155"
MATERIAL"X7R"
VOLTAGE"16V"
TOLERANCE"10%"
VALUE"0.22UF"
LOCATION"C3M4"
GROUP"PCIE_UPLINK"
ROOM"OCP_STEERING"
CDS_LOCATION"C3M4"
$SEC"1"
CDS_SEC"1"
CDS_LIB"mstr_discrete";
"A"
$PN"1"94;
"B"
$PN"2"28;
%"TAP"
"3","(1250,1575)","0","mstr_standard","I245";
;
CDS_LIB"mstr_standard"
BODY_TYPE"PLUMBING"
HDL_TAP"TRUE";
"B \NAC \NWC"2;
"S \NAC"
BN"14"92;
%"CAP"
"1","(1250,1325)","2","mstr_discrete","I246";
;
TOLERANCE"10%"
MATERIAL"X7R"
VOLTAGE"16V"
PACK_TYPE"0402"
VALUE"0.22UF"
PART_NUMBER"A36096-155"
LOCATION"C3M12"
GROUP"PCIE_UPLINK"
ROOM"OCP_STEERING"
CDS_LOCATION"C3M12"
$SEC"1"
CDS_SEC"1"
CDS_LIB"mstr_discrete";
"A"
$PN"1"92;
"B"
$PN"2"91;
%"CAP"
"1","(1000,2025)","2","mstr_discrete","I247";
;
GROUP"PCIE_UPLINK"
VALUE"0.22UF"
LOCATION"C3M2"
MATERIAL"X7R"
VOLTAGE"16V"
PACK_TYPE"0402"
TOLERANCE"10%"
PART_NUMBER"A36096-155"
ROOM"OCP_STEERING"
CDS_LOCATION"C3M2"
$SEC"1"
CDS_SEC"1"
CDS_LIB"mstr_discrete";
"A"
$PN"1"135;
"B"
$PN"2"139;
%"TAP"
"7","(1000,1775)","0","mstr_standard","I248";
;
CDS_LIB"mstr_standard"
BODY_TYPE"PLUMBING"
HDL_TAP"TRUE";
"B \NAC \NWC"1;
"S \NAC"
BN"15"139;
%"TAP"
"3","(100,3900)","0","mstr_standard","I25";
;
CDS_LIB"mstr_standard"
BODY_TYPE"PLUMBING"
HDL_TAP"TRUE";
"B \NAC \NWC"11;
"S \NAC"
BN"11"25;
%"TAP"
"3","(1050,1575)","0","mstr_standard","I250";
;
CDS_LIB"mstr_standard"
BODY_TYPE"PLUMBING"
HDL_TAP"TRUE";
"B \NAC \NWC"2;
"S \NAC"
BN"15"27;
%"TAP"
"7","(1450,775)","0","mstr_standard","I251";
;
CDS_LIB"mstr_standard"
BODY_TYPE"PLUMBING"
HDL_TAP"TRUE";
"B \NAC \NWC"5;
"S \NAC"
BN"13"89;
%"TAP"
"7","(1650,775)","0","mstr_standard","I252";
;
CDS_LIB"mstr_standard"
BODY_TYPE"PLUMBING"
HDL_TAP"TRUE";
"B \NAC \NWC"5;
"S \NAC"
BN"12"28;
%"CAP"
"1","(1450,1025)","2","mstr_discrete","I253";
;
PART_NUMBER"A36096-155"
PACK_TYPE"0402"
MATERIAL"X7R"
VOLTAGE"16V"
TOLERANCE"10%"
VALUE"0.22UF"
LOCATION"C3M14"
GROUP"PCIE_UPLINK"
ROOM"OCP_STEERING"
CDS_LOCATION"C3M14"
$SEC"1"
CDS_SEC"1"
CDS_LIB"mstr_discrete";
"A"
$PN"1"138;
"B"
$PN"2"89;
%"TAP"
"7","(1250,775)","0","mstr_standard","I254";
;
CDS_LIB"mstr_standard"
BODY_TYPE"PLUMBING"
HDL_TAP"TRUE";
"B \NAC \NWC"5;
"S \NAC"
BN"14"91;
%"CAP"
"1","(1050,1025)","2","mstr_discrete","I255";
;
MATERIAL"X7R"
VOLTAGE"16V"
PACK_TYPE"0402"
TOLERANCE"10%"
VALUE"0.22UF"
PART_NUMBER"A36096-155"
LOCATION"C3M1"
GROUP"PCIE_UPLINK"
ROOM"OCP_STEERING"
CDS_LOCATION"C3M1"
$SEC"1"
CDS_SEC"1"
CDS_LIB"mstr_discrete";
"A"
$PN"1"27;
"B"
$PN"2"88;
%"TAP"
"7","(1050,775)","0","mstr_standard","I256";
;
CDS_LIB"mstr_standard"
BODY_TYPE"PLUMBING"
HDL_TAP"TRUE";
"B \NAC \NWC"5;
"S \NAC"
BN"15"88;
%"CAP"
"1","(700,3650)","2","mstr_discrete","I257";
;
LOCATION"C7G19"
PART_NUMBER"A36096-155"
VALUE"0.22UF"
TOLERANCE"10%"
PACK_TYPE"0402"
VOLTAGE"16V"
MATERIAL"X7R"
SEC_TYPE"0402"
CDS_LIB"mstr_discrete"
SEC"1"
CDS_LOCATION"C7G19"
ROOM"OCP_STEERING"
CDS_SEC"1";
"A"
$PN"1"35;
"B"
$PN"2"34;
%"CAP"
"1","(650,4650)","2","mstr_discrete","I258";
;
MATERIAL"X7R"
VOLTAGE"16V"
PACK_TYPE"0402"
TOLERANCE"10%"
VALUE"0.22UF"
PART_NUMBER"A36096-155"
LOCATION"C7G20"
CDS_SEC"1"
ROOM"OCP_STEERING"
CDS_LOCATION"C7G20"
SEC"1"
CDS_LIB"mstr_discrete"
SEC_TYPE"0402";
"A"
$PN"1"37;
"B"
$PN"2"36;
%"TAP"
"7","(50,4100)","0","mstr_standard","I26";
;
CDS_LIB"mstr_standard"
BODY_TYPE"PLUMBING"
HDL_TAP"TRUE";
"B \NAC \NWC"10;
"S \NAC"
BN"11"105;
%"CAP"
"1","(-150,4650)","2","mstr_discrete","I27";
;
CDS_SEC"1"
MATERIAL"X7R"
VOLTAGE"16V"
PACK_TYPE"0402"
TOLERANCE"10%"
VALUE"0.22UF"
PART_NUMBER"A36096-155"
LOCATION"C7G11"
ROOM"OCP_STEERING"
CDS_LOCATION"C7G11"
SEC"1"
CDS_LIB"mstr_discrete"
SEC_TYPE"0402";
"A"
$PN"1"43;
"B"
$PN"2"86;
%"CAP"
"1","(50,4350)","2","mstr_discrete","I28";
;
CDS_SEC"1"
MATERIAL"X7R"
VOLTAGE"16V"
PACK_TYPE"0402"
TOLERANCE"10%"
VALUE"0.22UF"
PART_NUMBER"A36096-155"
LOCATION"C7G14"
ROOM"OCP_STEERING"
CDS_LOCATION"C7G14"
SEC"1"
CDS_LIB"mstr_discrete"
SEC_TYPE"0402";
"A"
$PN"1"108;
"B"
$PN"2"105;
%"TAP"
"7","(300,3100)","0","mstr_standard","I29";
;
CDS_LIB"mstr_standard"
BODY_TYPE"PLUMBING"
HDL_TAP"TRUE";
"B \NAC \NWC"4;
"S \NAC"
BN"10"56;
%"TAP"
"7","(500,3100)","0","mstr_standard","I30";
;
CDS_LIB"mstr_standard"
BODY_TYPE"PLUMBING"
HDL_TAP"TRUE";
"B \NAC \NWC"4;
"S \NAC"
BN"9"55;
%"CAP"
"1","(300,3650)","2","mstr_discrete","I31";
;
CDS_SEC"1"
PACK_TYPE"0402"
PART_NUMBER"A36096-155"
MATERIAL"X7R"
TOLERANCE"10%"
VOLTAGE"16V"
VALUE"0.22UF"
LOCATION"C7G16"
ROOM"OCP_STEERING"
CDS_LOCATION"C7G16"
SEC"1"
CDS_LIB"mstr_discrete"
SEC_TYPE"0402";
"A"
$PN"1"50;
"B"
$PN"2"56;
%"CAP"
"1","(500,3350)","2","mstr_discrete","I32";
;
CDS_SEC"1"
VOLTAGE"16V"
VALUE"0.22UF"
LOCATION"C7G18"
PACK_TYPE"0402"
PART_NUMBER"A36096-155"
MATERIAL"X7R"
TOLERANCE"10%"
ROOM"OCP_STEERING"
CDS_LOCATION"C7G18"
SEC"1"
CDS_LIB"mstr_discrete"
SEC_TYPE"0402";
"A"
$PN"1"48;
"B"
$PN"2"55;
%"TAP"
"7","(700,3100)","0","mstr_standard","I33";
;
CDS_LIB"mstr_standard"
BODY_TYPE"PLUMBING"
HDL_TAP"TRUE";
"B \NAC \NWC"4;
"S \NAC"
BN"8"34;
%"TAP"
"7","(925,3100)","0","mstr_standard","I35";
;
CDS_LIB"mstr_standard"
BODY_TYPE"PLUMBING"
HDL_TAP"TRUE";
"B \NAC \NWC"4;
"S \NAC"
BN"7"118;
%"TAP"
"7","(1125,3100)","0","mstr_standard","I36";
;
CDS_LIB"mstr_standard"
BODY_TYPE"PLUMBING"
HDL_TAP"TRUE";
"B \NAC \NWC"4;
"S \NAC"
BN"6"134;
%"CAP"
"1","(925,3350)","2","mstr_discrete","I37";
;
CDS_SEC"1"
MATERIAL"X7R"
VOLTAGE"16V"
PACK_TYPE"0402"
TOLERANCE"10%"
LOCATION"C7G22"
VALUE"0.22UF"
PART_NUMBER"A36096-155"
ROOM"OCP_STEERING"
CDS_LOCATION"C7G22"
SEC"1"
SEC_TYPE"0402"
CDS_LIB"mstr_discrete";
"A"
$PN"1"44;
"B"
$PN"2"118;
%"TAP"
"3","(300,3900)","0","mstr_standard","I38";
;
CDS_LIB"mstr_standard"
BODY_TYPE"PLUMBING"
HDL_TAP"TRUE";
"B \NAC \NWC"11;
"S \NAC"
BN"10"50;
%"TAP"
"7","(250,4100)","0","mstr_standard","I39";
;
CDS_LIB"mstr_standard"
BODY_TYPE"PLUMBING"
HDL_TAP"TRUE";
"B \NAC \NWC"10;
"S \NAC"
BN"10"106;
%"TAP"
"7","(-700,3100)","0","mstr_standard","I4";
;
CDS_LIB"mstr_standard"
BODY_TYPE"PLUMBING"
HDL_TAP"TRUE";
"B \NAC \NWC"4;
"S \NAC"
BN"15"51;
%"TAP"
"3","(500,3900)","0","mstr_standard","I40";
;
CDS_LIB"mstr_standard"
BODY_TYPE"PLUMBING"
HDL_TAP"TRUE";
"B \NAC \NWC"11;
"S \NAC"
BN"9"48;
%"TAP"
"7","(450,4100)","0","mstr_standard","I41";
;
CDS_LIB"mstr_standard"
BODY_TYPE"PLUMBING"
HDL_TAP"TRUE";
"B \NAC \NWC"10;
"S \NAC"
BN"9"107;
%"TAP"
"3","(700,3900)","0","mstr_standard","I42";
;
CDS_LIB"mstr_standard"
BODY_TYPE"PLUMBING"
HDL_TAP"TRUE";
"B \NAC \NWC"11;
"S \NAC"
BN"8"35;
%"TAP"
"7","(650,4100)","0","mstr_standard","I43";
;
CDS_LIB"mstr_standard"
BODY_TYPE"PLUMBING"
HDL_TAP"TRUE";
"B \NAC \NWC"10;
"S \NAC"
BN"8"36;
%"CAP"
"1","(450,4350)","2","mstr_discrete","I44";
;
CDS_SEC"1"
MATERIAL"X7R"
VOLTAGE"16V"
PACK_TYPE"0402"
TOLERANCE"10%"
VALUE"0.22UF"
PART_NUMBER"A36096-155"
LOCATION"C7G17"
ROOM"OCP_STEERING"
CDS_LOCATION"C7G17"
SEC"1"
CDS_LIB"mstr_discrete"
SEC_TYPE"0402";
"A"
$PN"1"42;
"B"
$PN"2"107;
%"CAP"
"1","(250,4650)","2","mstr_discrete","I45";
;
CDS_SEC"1"
MATERIAL"X7R"
PACK_TYPE"0402"
TOLERANCE"10%"
PART_NUMBER"A36096-155"
LOCATION"C7G15"
VALUE"0.22UF"
VOLTAGE"16V"
ROOM"OCP_STEERING"
CDS_LOCATION"C7G15"
SEC"1"
CDS_LIB"mstr_discrete"
SEC_TYPE"0402";
"A"
$PN"1"109;
"B"
$PN"2"106;
%"TAP"
"3","(925,3900)","0","mstr_standard","I47";
;
CDS_LIB"mstr_standard"
BODY_TYPE"PLUMBING"
HDL_TAP"TRUE";
"B \NAC \NWC"11;
"S \NAC"
BN"7"44;
%"TAP"
"7","(875,4100)","0","mstr_standard","I48";
;
CDS_LIB"mstr_standard"
BODY_TYPE"PLUMBING"
HDL_TAP"TRUE";
"B \NAC \NWC"10;
"S \NAC"
BN"7"47;
%"TAP"
"7","(1075,4100)","0","mstr_standard","I49";
;
CDS_LIB"mstr_standard"
BODY_TYPE"PLUMBING"
HDL_TAP"TRUE";
"B \NAC \NWC"10;
"S \NAC"
BN"6"39;
%"TAP"
"7","(-500,3100)","0","mstr_standard","I5";
;
CDS_LIB"mstr_standard"
BODY_TYPE"PLUMBING"
HDL_TAP"TRUE";
"B \NAC \NWC"4;
"S \NAC"
BN"14"52;
%"TAP"
"3","(1125,3900)","0","mstr_standard","I50";
;
CDS_LIB"mstr_standard"
BODY_TYPE"PLUMBING"
HDL_TAP"TRUE";
"B \NAC \NWC"11;
"S \NAC"
BN"6"45;
%"CAP"
"1","(875,4350)","2","mstr_discrete","I51";
;
CDS_SEC"1"
PACK_TYPE"0402"
PART_NUMBER"A36096-155"
MATERIAL"X7R"
TOLERANCE"10%"
VOLTAGE"16V"
VALUE"0.22UF"
LOCATION"C7G21"
ROOM"OCP_STEERING"
CDS_LOCATION"C7G21"
SEC"1"
SEC_TYPE"0402"
CDS_LIB"mstr_discrete";
"A"
$PN"1"40;
"B"
$PN"2"47;
%"CAP"
"1","(1075,4650)","2","mstr_discrete","I52";
;
CDS_SEC"1"
PACK_TYPE"0402"
TOLERANCE"10%"
MATERIAL"X7R"
VOLTAGE"16V"
LOCATION"C7G23"
PART_NUMBER"A36096-155"
VALUE"0.22UF"
ROOM"OCP_STEERING"
CDS_LOCATION"C7G23"
SEC"1"
SEC_TYPE"0402"
CDS_LIB"mstr_discrete";
"A"
$PN"1"112;
"B"
$PN"2"39;
%"TAP"
"7","(1525,3100)","0","mstr_standard","I53";
;
CDS_LIB"mstr_standard"
BODY_TYPE"PLUMBING"
HDL_TAP"TRUE";
"B \NAC \NWC"4;
"S \NAC"
BN"4"58;
%"TAP"
"7","(1325,3100)","0","mstr_standard","I54";
;
CDS_LIB"mstr_standard"
BODY_TYPE"PLUMBING"
HDL_TAP"TRUE";
"B \NAC \NWC"4;
"S \NAC"
BN"5"57;
%"CAP"
"1","(1325,3350)","2","mstr_discrete","I55";
;
CDS_SEC"1"
MATERIAL"X7R"
VOLTAGE"16V"
PACK_TYPE"0402"
TOLERANCE"10%"
VALUE"0.22UF"
LOCATION"C7G26"
PART_NUMBER"A36096-155"
ROOM"OCP_STEERING"
CDS_LOCATION"C7G26"
SEC"1"
SEC_TYPE"0402"
CDS_LIB"mstr_discrete";
"A"
$PN"1"98;
"B"
$PN"2"57;
%"CAP"
"1","(1725,3350)","2","mstr_discrete","I56";
;
CDS_SEC"1"
MATERIAL"X7R"
VOLTAGE"16V"
PACK_TYPE"0402"
VALUE"0.22UF"
LOCATION"C8G4"
TOLERANCE"10%"
PART_NUMBER"A36096-155"
ROOM"OCP_STEERING"
CDS_LOCATION"C8G4"
SEC"1"
SEC_TYPE"0402"
CDS_LIB"mstr_discrete";
"A"
$PN"1"100;
"B"
$PN"2"59;
%"TAP"
"7","(1725,3100)","0","mstr_standard","I57";
;
CDS_LIB"mstr_standard"
BODY_TYPE"PLUMBING"
HDL_TAP"TRUE";
"B \NAC \NWC"4;
"S \NAC"
BN"3"59;
%"CAP"
"1","(1525,3650)","2","mstr_discrete","I58";
;
CDS_SEC"1"
MATERIAL"X7R"
VOLTAGE"16V"
PART_NUMBER"A36096-155"
LOCATION"C8G2"
TOLERANCE"10%"
VALUE"0.22UF"
PACK_TYPE"0402"
ROOM"OCP_STEERING"
CDS_LOCATION"C8G2"
SEC"1"
SEC_TYPE"0402"
CDS_LIB"mstr_discrete";
"A"
$PN"1"99;
"B"
$PN"2"58;
%"TAP"
"7","(2125,3100)","0","mstr_standard","I59";
;
CDS_LIB"mstr_standard"
BODY_TYPE"PLUMBING"
HDL_TAP"TRUE";
"B \NAC \NWC"4;
"S \NAC"
BN"1"61;
%"CAP"
"1","(-700,3350)","2","mstr_discrete","I6";
;
MATERIAL"X7R"
VOLTAGE"16V"
TOLERANCE"10%"
VALUE"0.22UF"
PART_NUMBER"A36096-155"
LOCATION"C7G6"
PACK_TYPE"0402"
ROOM"OCP_STEERING"
CDS_LOCATION"C7G6"
$SEC"1"
CDS_SEC"1"
CDS_LIB"mstr_discrete";
"A"
$PN"1"77;
"B"
$PN"2"51;
%"TAP"
"7","(1925,3100)","0","mstr_standard","I60";
;
CDS_LIB"mstr_standard"
BODY_TYPE"PLUMBING"
HDL_TAP"TRUE";
"B \NAC \NWC"4;
"S \NAC"
BN"2"60;
%"CAP"
"1","(1925,3650)","2","mstr_discrete","I61";
;
CDS_SEC"1"
PACK_TYPE"0402"
TOLERANCE"10%"
PART_NUMBER"A36096-155"
LOCATION"C8G6"
VOLTAGE"16V"
VALUE"0.22UF"
MATERIAL"X7R"
ROOM"OCP_STEERING"
CDS_LOCATION"C8G6"
SEC"1"
SEC_TYPE"0402"
CDS_LIB"mstr_discrete";
"A"
$PN"1"101;
"B"
$PN"2"60;
%"CAP"
"1","(2125,3350)","2","mstr_discrete","I62";
;
CDS_SEC"1"
MATERIAL"X7R"
VOLTAGE"16V"
PACK_TYPE"0402"
TOLERANCE"10%"
VALUE"0.22UF"
LOCATION"C8G7"
PART_NUMBER"A36096-155"
ROOM"OCP_STEERING"
CDS_LOCATION"C8G7"
SEC"1"
SEC_TYPE"0402"
CDS_LIB"mstr_discrete";
"A"
$PN"1"33;
"B"
$PN"2"61;
%"TAP"
"3","(1325,3900)","0","mstr_standard","I63";
;
CDS_LIB"mstr_standard"
BODY_TYPE"PLUMBING"
HDL_TAP"TRUE";
"B \NAC \NWC"11;
"S \NAC"
BN"5"98;
%"TAP"
"7","(1275,4100)","0","mstr_standard","I64";
;
CDS_LIB"mstr_standard"
BODY_TYPE"PLUMBING"
HDL_TAP"TRUE";
"B \NAC \NWC"10;
"S \NAC"
BN"5"110;
%"TAP"
"3","(1525,3900)","0","mstr_standard","I65";
;
CDS_LIB"mstr_standard"
BODY_TYPE"PLUMBING"
HDL_TAP"TRUE";
"B \NAC \NWC"11;
"S \NAC"
BN"4"99;
%"TAP"
"7","(1475,4100)","0","mstr_standard","I66";
;
CDS_LIB"mstr_standard"
BODY_TYPE"PLUMBING"
HDL_TAP"TRUE";
"B \NAC \NWC"10;
"S \NAC"
BN"4"38;
%"TAP"
"7","(1675,4100)","0","mstr_standard","I67";
;
CDS_LIB"mstr_standard"
BODY_TYPE"PLUMBING"
HDL_TAP"TRUE";
"B \NAC \NWC"10;
"S \NAC"
BN"3"113;
%"TAP"
"3","(1725,3900)","0","mstr_standard","I68";
;
CDS_LIB"mstr_standard"
BODY_TYPE"PLUMBING"
HDL_TAP"TRUE";
"B \NAC \NWC"11;
"S \NAC"
BN"3"100;
%"CAP"
"1","(1275,4350)","2","mstr_discrete","I69";
;
CDS_SEC"1"
MATERIAL"X7R"
VOLTAGE"16V"
PACK_TYPE"0402"
TOLERANCE"10%"
VALUE"0.22UF"
PART_NUMBER"A36096-155"
LOCATION"C7G25"
ROOM"OCP_STEERING"
CDS_LOCATION"C7G25"
SEC"1"
SEC_TYPE"0402"
CDS_LIB"mstr_discrete";
"A"
$PN"1"111;
"B"
$PN"2"110;
%"CAP"
"1","(-500,3650)","2","mstr_discrete","I7";
;
CDS_SEC"1"
MATERIAL"X7R"
VOLTAGE"16V"
PACK_TYPE"0402"
TOLERANCE"10%"
VALUE"0.22UF"
PART_NUMBER"A36096-155"
LOCATION"C7G7"
ROOM"OCP_STEERING"
CDS_LOCATION"C7G7"
SEC"1"
CDS_LIB"mstr_discrete"
SEC_TYPE"0402";
"A"
$PN"1"79;
"B"
$PN"2"52;
%"CAP"
"1","(1475,4650)","2","mstr_discrete","I70";
;
CDS_SEC"1"
MATERIAL"X7R"
VOLTAGE"16V"
PACK_TYPE"0402"
TOLERANCE"10%"
VALUE"0.22UF"
LOCATION"C8G1"
PART_NUMBER"A36096-155"
ROOM"OCP_STEERING"
CDS_LOCATION"C8G1"
SEC"1"
SEC_TYPE"0402"
CDS_LIB"mstr_discrete";
"A"
$PN"1"123;
"B"
$PN"2"38;
%"CAP"
"1","(1675,4350)","2","mstr_discrete","I71";
;
CDS_SEC"1"
MATERIAL"X7R"
VOLTAGE"16V"
TOLERANCE"10%"
VALUE"0.22UF"
LOCATION"C8G3"
PART_NUMBER"A36096-155"
PACK_TYPE"0402"
ROOM"OCP_STEERING"
CDS_LOCATION"C8G3"
SEC"1"
SEC_TYPE"0402"
CDS_LIB"mstr_discrete";
"A"
$PN"1"41;
"B"
$PN"2"113;
%"TAP"
"7","(1875,4100)","0","mstr_standard","I72";
;
CDS_LIB"mstr_standard"
BODY_TYPE"PLUMBING"
HDL_TAP"TRUE";
"B \NAC \NWC"10;
"S \NAC"
BN"2"32;
%"TAP"
"3","(2125,3900)","0","mstr_standard","I73";
;
CDS_LIB"mstr_standard"
BODY_TYPE"PLUMBING"
HDL_TAP"TRUE";
"B \NAC \NWC"11;
"S \NAC"
BN"1"33;
%"TAP"
"7","(2075,4100)","0","mstr_standard","I74";
;
CDS_LIB"mstr_standard"
BODY_TYPE"PLUMBING"
HDL_TAP"TRUE";
"B \NAC \NWC"10;
"S \NAC"
BN"1"115;
%"CAP"
"1","(1875,4650)","2","mstr_discrete","I75";
;
CDS_SEC"1"
MATERIAL"X7R"
VOLTAGE"16V"
PACK_TYPE"0402"
TOLERANCE"10%"
VALUE"0.22UF"
LOCATION"C8G5"
PART_NUMBER"A36096-155"
ROOM"OCP_STEERING"
CDS_LOCATION"C8G5"
SEC"1"
SEC_TYPE"0402"
CDS_LIB"mstr_discrete";
"A"
$PN"1"114;
"B"
$PN"2"32;
%"CAP"
"1","(2075,4350)","2","mstr_discrete","I76";
;
CDS_SEC"1"
MATERIAL"X7R"
PACK_TYPE"0402"
VALUE"0.22UF"
LOCATION"C8G8"
VOLTAGE"16V"
TOLERANCE"10%"
PART_NUMBER"A36096-155"
ROOM"OCP_STEERING"
CDS_LOCATION"C8G8"
SEC"1"
SEC_TYPE"0402"
CDS_LIB"mstr_discrete";
"A"
$PN"1"116;
"B"
$PN"2"115;
%"TAP"
"3","(-750,4900)","0","mstr_standard","I78";
;
CDS_LIB"mstr_standard"
BODY_TYPE"PLUMBING"
HDL_TAP"TRUE";
"B \NAC \NWC"8;
"S \NAC"
BN"15"83;
%"TAP"
"3","(-550,4900)","0","mstr_standard","I79";
;
CDS_LIB"mstr_standard"
BODY_TYPE"PLUMBING"
HDL_TAP"TRUE";
"B \NAC \NWC"8;
"S \NAC"
BN"14"84;
%"CAP"
"1","(-300,3350)","2","mstr_discrete","I8";
;
CDS_SEC"1"
MATERIAL"X7R"
VOLTAGE"16V"
TOLERANCE"10%"
VALUE"0.22UF"
PART_NUMBER"A36096-155"
LOCATION"C7G10"
PACK_TYPE"0402"
ROOM"OCP_STEERING"
CDS_LOCATION"C7G10"
SEC"1"
CDS_LIB"mstr_discrete"
SEC_TYPE"0402";
"A"
$PN"1"78;
"B"
$PN"2"24;
%"TAP"
"3","(-350,4900)","0","mstr_standard","I80";
;
CDS_LIB"mstr_standard"
BODY_TYPE"PLUMBING"
HDL_TAP"TRUE";
"B \NAC \NWC"8;
"S \NAC"
BN"13"87;
%"TAP"
"3","(-150,4900)","0","mstr_standard","I81";
;
CDS_LIB"mstr_standard"
BODY_TYPE"PLUMBING"
HDL_TAP"TRUE";
"B \NAC \NWC"8;
"S \NAC"
BN"12"43;
%"TAP"
"3","(450,4900)","0","mstr_standard","I82";
;
CDS_LIB"mstr_standard"
BODY_TYPE"PLUMBING"
HDL_TAP"TRUE";
"B \NAC \NWC"8;
"S \NAC"
BN"9"42;
%"TAP"
"3","(250,4900)","0","mstr_standard","I83";
;
CDS_LIB"mstr_standard"
BODY_TYPE"PLUMBING"
HDL_TAP"TRUE";
"B \NAC \NWC"8;
"S \NAC"
BN"10"109;
%"TAP"
"3","(650,4900)","0","mstr_standard","I84";
;
CDS_LIB"mstr_standard"
BODY_TYPE"PLUMBING"
HDL_TAP"TRUE";
"B \NAC \NWC"8;
"S \NAC"
BN"8"37;
%"TAP"
"3","(875,4900)","0","mstr_standard","I85";
;
CDS_LIB"mstr_standard"
BODY_TYPE"PLUMBING"
HDL_TAP"TRUE";
"B \NAC \NWC"8;
"S \NAC"
BN"7"40;
%"TAP"
"3","(1075,4900)","0","mstr_standard","I86";
;
CDS_LIB"mstr_standard"
BODY_TYPE"PLUMBING"
HDL_TAP"TRUE";
"B \NAC \NWC"8;
"S \NAC"
BN"6"112;
%"TAP"
"3","(1275,4900)","0","mstr_standard","I87";
;
CDS_LIB"mstr_standard"
BODY_TYPE"PLUMBING"
HDL_TAP"TRUE";
"B \NAC \NWC"8;
"S \NAC"
BN"5"111;
%"TAP"
"3","(1475,4900)","0","mstr_standard","I88";
;
CDS_LIB"mstr_standard"
BODY_TYPE"PLUMBING"
HDL_TAP"TRUE";
"B \NAC \NWC"8;
"S \NAC"
BN"4"123;
%"TAP"
"3","(1675,4900)","0","mstr_standard","I89";
;
CDS_LIB"mstr_standard"
BODY_TYPE"PLUMBING"
HDL_TAP"TRUE";
"B \NAC \NWC"8;
"S \NAC"
BN"3"41;
%"TAP"
"7","(-300,3100)","0","mstr_standard","I9";
;
CDS_LIB"mstr_standard"
BODY_TYPE"PLUMBING"
HDL_TAP"TRUE";
"B \NAC \NWC"4;
"S \NAC"
BN"13"24;
%"TAP"
"3","(1875,4900)","0","mstr_standard","I90";
;
CDS_LIB"mstr_standard"
BODY_TYPE"PLUMBING"
HDL_TAP"TRUE";
"B \NAC \NWC"8;
"S \NAC"
BN"2"114;
%"TAP"
"3","(2075,4900)","0","mstr_standard","I91";
;
CDS_LIB"mstr_standard"
BODY_TYPE"PLUMBING"
HDL_TAP"TRUE";
"B \NAC \NWC"8;
"S \NAC"
BN"1"116;
%"TAP"
"3","(2275,4900)","0","mstr_standard","I92";
;
CDS_LIB"mstr_standard"
BODY_TYPE"PLUMBING"
HDL_TAP"TRUE";
"B \NAC \NWC"8;
"S \NAC"
BN"0"117;
%"CAP"
"1","(2275,4650)","2","mstr_discrete","I93";
;
CDS_SEC"1"
MATERIAL"X7R"
VOLTAGE"16V"
PACK_TYPE"0402"
TOLERANCE"10%"
VALUE"0.22UF"
LOCATION"C8G9"
PART_NUMBER"A36096-155"
ROOM"OCP_STEERING"
CDS_LOCATION"C8G9"
SEC"1"
SEC_TYPE"0402"
CDS_LIB"mstr_discrete";
"A"
$PN"1"117;
"B"
$PN"2"46;
%"TAP"
"7","(2325,3100)","0","mstr_standard","I94";
;
CDS_LIB"mstr_standard"
BODY_TYPE"PLUMBING"
HDL_TAP"TRUE";
"B \NAC \NWC"4;
"S \NAC"
BN"0"49;
%"CAP"
"1","(2325,3650)","2","mstr_discrete","I96";
;
CDS_SEC"1"
TOLERANCE"10%"
MATERIAL"X7R"
VOLTAGE"16V"
PACK_TYPE"0402"
PART_NUMBER"A36096-155"
VALUE"0.22UF"
LOCATION"C8G10"
ROOM"OCP_STEERING"
CDS_LOCATION"C8G10"
SEC"1"
SEC_TYPE"0402"
CDS_LIB"mstr_discrete";
"A"
$PN"1"104;
"B"
$PN"2"49;
%"TAP"
"3","(2325,3900)","0","mstr_standard","I97";
;
CDS_LIB"mstr_standard"
BODY_TYPE"PLUMBING"
HDL_TAP"TRUE";
"B \NAC \NWC"11;
"S \NAC"
BN"0"104;
%"TAP"
"7","(2275,4100)","0","mstr_standard","I98";
;
CDS_LIB"mstr_standard"
BODY_TYPE"PLUMBING"
HDL_TAP"TRUE";
"B \NAC \NWC"10;
"S \NAC"
BN"0"46;
END.
